# T6G (Grand Teton) — schematic netlist excerpt (pin names and nets, part order shuffled) for the footprints in the layout excerpt that follows; sources: Cadence DE-HDL packaged netlist, KiCad conversion of 04192023_DAF0TMB3IC0_F0TG_MB_C_brd_V02_OCP.brd

R1437  Q_RES  1K 1% CHIP  pkg 0201LF  page 185 : A = P1V8_CPU1_RT_1D ; B = SMB_RT_CPU1_P0_ROM_MUX_1D_SCL
R51  Q_RES  0 5% CHIP  pkg 0402LF  page 80 : A = SMB_1_PLD_3V3AUX_SCL_R1 ; B = SMB_1_PLD_3V3AUX_SCL_R2
C763  Q_CAP_DIFFBUS  DIFF BUS_0.22UF 6.3V 20% X6S  pkg C0201  page 66 : \1\ = P5E_CPU1_P2_TX_C_DP<5> ; \2\ = P5E_CPU1_P2_TX_DP<5>

(kicad_pcb
	(version 20260206)
	(generator "pcbnew")
	(generator_version "10.0")
	(general
		(thickness 1.6)
		(legacy_teardrops no)
	)
	(paper "A4")
	(title_block
		(title "04192023_DAF0TMB3IC0_F0TG_MB_C_brd_V02_OCP.brd")
		(comment 1 "Grand Teton / footprints 1412-1414 of 8354")
	)
	(layers
		(0 "F.Cu" signal "TOP")
		(4 "In1.Cu" signal "GND")
		(6 "In2.Cu" signal "IN1")
		(8 "In3.Cu" signal "GND1")
		(10 "In4.Cu" signal "IN2")
		(12 "In5.Cu" signal "GND2")
		(14 "In6.Cu" signal "IN3")
		(16 "In7.Cu" signal "GND3")
		(18 "In8.Cu" signal "VCC")
		(20 "In9.Cu" signal "VCC1")
		(22 "In10.Cu" signal "GND4")
		(24 "In11.Cu" signal "IN4")
		(26 "In12.Cu" signal "GND5")
		(28 "In13.Cu" signal "IN5")
		(30 "In14.Cu" signal "GND6")
		(32 "In15.Cu" signal "IN6")
		(34 "In16.Cu" signal "GND7")
		(2 "B.Cu" signal "BOTTOM")
		(9 "F.Adhes" user "F.Adhesive")
		(11 "B.Adhes" user "B.Adhesive")
		(13 "F.Paste" user "Package Geometry/Pastemask Top")
		(15 "B.Paste" user "Package Geometry/Pastemask Bottom")
		(5 "F.SilkS" user "Ref Des/Silkscreen Top")
		(7 "B.SilkS" user "Ref Des/Silkscreen Bottom")
		(1 "F.Mask" user "Board Geometry/Soldermask Top")
		(3 "B.Mask" user "Board Geometry/Soldermask Bottom")
		(17 "Dwgs.User" user "User.Drawings")
		(19 "Cmts.User" user "User.Comments")
		(21 "Eco1.User" user "User.Eco1")
		(23 "Eco2.User" user "User.Eco2")
		(25 "Edge.Cuts" user "Board Geometry/Outline")
		(27 "Margin" user)
		(31 "F.CrtYd" user "Package Geometry/Place Bound Top")
		(29 "B.CrtYd" user "Package Geometry/Place Bound Bottom")
		(35 "F.Fab" user "Ref Des/Assembly Top")
		(33 "B.Fab" user "Ref Des/Assembly Bottom")
	)
	(footprint ""
		(layer "F.Cu")
		(at 94.1832 -401.9804 180)
		(property "Reference" "R1437"
			(at 0 0 180)
			(layer "F.SilkS")
			(hide yes)
			(effects
				(font
					(size 1.27 1.27)
				)
			)
		)
		(property "Value" ""
			(at 0 0 180)
			(layer "F.Fab")
			(effects
				(font
					(size 1.27 1.27)
				)
			)
		)
		(duplicate_pad_numbers_are_jumpers no)
		(fp_line
			(start 0.32512 0.175006)
			(end -0.32512 0.175006)
			(stroke
				(width 0.1)
				(type default)
			)
			(layer "F.Fab")
		)
		(fp_line
			(start 0.32512 -0.175006)
			(end 0.32512 0.175006)
			(stroke
				(width 0.1)
				(type default)
			)
			(layer "F.Fab")
		)
		(fp_line
			(start -0.32512 0.175006)
			(end -0.32512 -0.175006)
			(stroke
				(width 0.1)
				(type default)
			)
			(layer "F.Fab")
		)
		(fp_line
			(start -0.32512 -0.175006)
			(end 0.32512 -0.175006)
			(stroke
				(width 0.1)
				(type default)
			)
			(layer "F.Fab")
		)
		(pad "1" smd rect
			(at -0.2667 0 180)
			(size 0.3048 0.381)
			(layers "F.Cu" "F.Mask" "F.Paste")
			(net "P1V8_CPU1_RT_1D")
		)
		(pad "2" smd rect
			(at 0.2667 0)
			(size 0.3048 0.381)
			(layers "F.Cu" "F.Mask" "F.Paste")
			(net "SMB_RT_CPU1_P0_ROM_MUX_1D_SCL")
		)
	)
	(footprint ""
		(layer "F.Cu")
		(at 149.424644 -373.03583 -90)
		(property "Reference" "C763"
			(at 0 0 270)
			(layer "F.SilkS")
			(hide yes)
			(effects
				(font
					(size 1.27 1.27)
				)
			)
		)
		(property "Value" ""
			(at 0 0 270)
			(layer "F.Fab")
			(effects
				(font
					(size 1.27 1.27)
				)
			)
		)
		(duplicate_pad_numbers_are_jumpers no)
		(fp_line
			(start -0.299974 0.150114)
			(end -0.299974 -0.150114)
			(stroke
				(width 0.1)
				(type default)
			)
			(layer "F.Fab")
		)
		(fp_line
			(start 0.299974 0.150114)
			(end -0.299974 0.150114)
			(stroke
				(width 0.1)
				(type default)
			)
			(layer "F.Fab")
		)
		(fp_line
			(start -0.299974 -0.150114)
			(end 0.299974 -0.150114)
			(stroke
				(width 0.1)
				(type default)
			)
			(layer "F.Fab")
		)
		(fp_line
			(start 0.299974 -0.150114)
			(end 0.299974 0.150114)
			(stroke
				(width 0.1)
				(type default)
			)
			(layer "F.Fab")
		)
		(pad "1" smd rect
			(at -0.2667 0 270)
			(size 0.3048 0.381)
			(layers "F.Cu" "F.Mask" "F.Paste")
			(net "P5E_CPU1_P2_TX_C_DP<5>")
		)
		(pad "2" smd rect
			(at 0.2667 0 270)
			(size 0.3048 0.381)
			(layers "F.Cu" "F.Mask" "F.Paste")
			(net "P5E_CPU1_P2_TX_DP<5>")
		)
	)
	(footprint ""
		(layer "F.Cu")
		(at 171.196 -116.296948)
		(property "Reference" "R51"
			(at 0 0 0)
			(layer "F.SilkS")
			(hide yes)
			(effects
				(font
					(size 1.27 1.27)
				)
			)
		)
		(property "Value" ""
			(at 0 0 0)
			(layer "F.Fab")
			(effects
				(font
					(size 1.27 1.27)
				)
			)
		)
		(duplicate_pad_numbers_are_jumpers no)
		(fp_line
			(start -0.7874 -0.4064)
			(end 0.7874 -0.4064)
			(stroke
				(width 0.1524)
				(type default)
			)
			(layer "F.SilkS")
		)
		(fp_line
			(start -0.7874 0.4064)
			(end -0.7874 -0.4064)
			(stroke
				(width 0.1524)
				(type default)
			)
			(layer "F.SilkS")
		)
		(fp_line
			(start 0.7874 -0.4064)
			(end 0.7874 0.4064)
			(stroke
				(width 0.1524)
				(type default)
			)
			(layer "F.SilkS")
		)
		(fp_line
			(start 0.7874 0.4064)
			(end -0.7874 0.4064)
			(stroke
				(width 0.1524)
				(type default)
			)
			(layer "F.SilkS")
		)
		(fp_line
			(start -0.67945 -0.305054)
			(end -0.12065 -0.305054)
			(stroke
				(width 0.1)
				(type default)
			)
			(layer "F.Fab")
		)
		(fp_line
			(start -0.67945 0.3048)
			(end -0.67945 -0.305054)
			(stroke
				(width 0.1)
				(type default)
			)
			(layer "F.Fab")
		)
		(fp_line
			(start -0.12065 -0.305054)
			(end -0.12065 -0.2794)
			(stroke
				(width 0.1)
				(type default)
			)
			(layer "F.Fab")
		)
		(fp_line
			(start -0.12065 -0.2794)
			(end 0.12065 -0.2794)
			(stroke
				(width 0.1)
				(type default)
			)
			(layer "F.Fab")
		)
		(fp_line
			(start -0.12065 0.2794)
			(end -0.12065 0.3048)
			(stroke
				(width 0.1)
				(type default)
			)
			(layer "F.Fab")
		)
		(fp_line
			(start -0.12065 0.3048)
			(end -0.67945 0.3048)
			(stroke
				(width 0.1)
				(type default)
			)
			(layer "F.Fab")
		)
		(fp_line
			(start 0.120396 0.2794)
			(end -0.12065 0.2794)
			(stroke
				(width 0.1)
				(type default)
			)
			(layer "F.Fab")
		)
		(fp_line
			(start 0.120396 0.3048)
			(end 0.120396 0.2794)
			(stroke
				(width 0.1)
				(type default)
			)
			(layer "F.Fab")
		)
		(fp_line
			(start 0.12065 -0.3048)
			(end 0.67945 -0.3048)
			(stroke
				(width 0.1)
				(type default)
			)
			(layer "F.Fab")
		)
		(fp_line
			(start 0.12065 -0.2794)
			(end 0.12065 -0.3048)
			(stroke
				(width 0.1)
				(type default)
			)
			(layer "F.Fab")
		)
		(fp_line
			(start 0.67945 -0.3048)
			(end 0.67945 0.3048)
			(stroke
				(width 0.1)
				(type default)
			)
			(layer "F.Fab")
		)
		(fp_line
			(start 0.67945 0.3048)
			(end 0.120396 0.3048)
			(stroke
				(width 0.1)
				(type default)
			)
			(layer "F.Fab")
		)
		(pad "1" smd circle
			(at -0.40005 0)
			(size 0 0)
			(layers "F.Cu" "F.Mask" "F.Paste")
			(net "SMB_1_PLD_3V3AUX_SCL_R1")
		)
		(pad "2" smd circle
			(at 0.40005 0)
			(size 0 0)
			(layers "F.Cu" "F.Mask" "F.Paste")
			(net "SMB_1_PLD_3V3AUX_SCL_R2")
		)
	)
)
